(kicad_pcb
	(version 20260206)
	(generator "pcbnew")
	(generator_version "10.0")
	(general
		(thickness 1.6)
		(legacy_teardrops no)
	)
	(paper "A4")
	(title_block
		(title "01162023_DA0F0TEBIF0_F0T_Expander_BD_F_brd_V02_OCP.brd")
		(comment 1 "Grand Teton / footprint 383 of 9728 (J11), pads 1-76 of 138")
	)
	(layers
		(0 "F.Cu" signal "TOP")
		(4 "In1.Cu" signal "GND")
		(6 "In2.Cu" signal "VCC")
		(8 "In3.Cu" signal "VCC1")
		(10 "In4.Cu" signal "GND1")
		(12 "In5.Cu" signal "IN1")
		(14 "In6.Cu" signal "GND2")
		(16 "In7.Cu" signal "IN2")
		(18 "In8.Cu" signal "GND3")
		(20 "In9.Cu" signal "IN3")
		(22 "In10.Cu" signal "GND4")
		(24 "In11.Cu" signal "IN4")
		(26 "In12.Cu" signal "GND5")
		(28 "In13.Cu" signal "IN5")
		(30 "In14.Cu" signal "GND6")
		(32 "In15.Cu" signal "IN6")
		(34 "In16.Cu" signal "GND7")
		(2 "B.Cu" signal "BOTTOM")
		(9 "F.Adhes" user "F.Adhesive")
		(11 "B.Adhes" user "B.Adhesive")
		(13 "F.Paste" user "Package Geometry/Pastemask Top")
		(15 "B.Paste" user "Package Geometry/Pastemask Bottom")
		(5 "F.SilkS" user "Ref Des/Silkscreen Top")
		(7 "B.SilkS" user "Ref Des/Silkscreen Bottom")
		(1 "F.Mask" user "Board Geometry/Soldermask Top")
		(3 "B.Mask" user "Board Geometry/Soldermask Bottom")
		(17 "Dwgs.User" user "User.Drawings")
		(19 "Cmts.User" user "User.Comments")
		(21 "Eco1.User" user "User.Eco1")
		(23 "Eco2.User" user "User.Eco2")
		(25 "Edge.Cuts" user "Board Geometry/Outline")
		(27 "Margin" user)
		(31 "F.CrtYd" user "Package Geometry/Place Bound Top")
		(29 "B.CrtYd" user "Package Geometry/Place Bound Bottom")
		(35 "F.Fab" user "Ref Des/Assembly Top")
		(33 "B.Fab" user "Ref Des/Assembly Bottom")
	)
	(footprint ""
		(layer "F.Cu")
		(at 71.90994 -412.090108)
		(property "Reference" "J11"
			(at -5.90423 3.675888 90)
			(unlocked yes)
			(layer "F.SilkS")
			(effects
				(font
					(size 2.032 1.524)
					(thickness 0.1524)
				)
				(justify left)
			)
		)
		(property "Value" ""
			(at 0 0 0)
			(layer "F.Fab")
			(effects
				(font
					(size 1.27 1.27)
				)
			)
		)
		(duplicate_pad_numbers_are_jumpers no)
		(pad "A1" thru_hole rect
			(at 0 0 180)
			(size 0.71628 0.71628)
			(drill 0.30988)
			(layers "*.Cu" "*.Mask")
			(remove_unused_layers no)
			(net "RST_MB_PERST_2_N")
			(clearance 0.0508)
			(thermal_gap 0.0508)
			(padstack
				(mode front_inner_back)
				(layer "Inner"
					(shape circle)
					(size 0.71628 0.71628)
					(clearance 0.0508)
				)
				(layer "B.Cu"
					(shape rect)
					(size 0.71628 0.71628)
					(clearance 0.0508)
				)
			)
		)
		(pad "A2" thru_hole circle
			(at 2.199894 0.199898 180)
			(size 0.906272 0.906272)
			(drill 0.499872)
			(layers "*.Cu" "*.Mask")
			(remove_unused_layers no)
			(net "GND")
			(clearance 0.0508)
			(thermal_gap 0.0508)
		)
		(pad "A3" thru_hole circle
			(at 4.400042 0 180)
			(size 0.71628 0.71628)
			(drill 0.30988)
			(layers "*.Cu" "*.Mask")
			(remove_unused_layers no)
			(net "GPU_HGX_DETECT_R_N")
			(clearance 0.0508)
			(thermal_gap 0.0508)
		)
		(pad "A4" thru_hole circle
			(at 6.599936 0.199898 180)
			(size 0.906272 0.906272)
			(drill 0.499872)
			(layers "*.Cu" "*.Mask")
			(remove_unused_layers no)
			(net "GND")
			(clearance 0.0508)
			(thermal_gap 0.0508)
		)
		(pad "A5" thru_hole circle
			(at 8.800084 0 180)
			(size 0.71628 0.71628)
			(drill 0.30988)
			(layers "*.Cu" "*.Mask")
			(remove_unused_layers no)
			(net "RST_MB_PERST_1_N")
			(clearance 0.0508)
			(thermal_gap 0.0508)
		)
		(pad "A6" thru_hole circle
			(at 10.999978 0.199898 180)
			(size 0.906272 0.906272)
			(drill 0.499872)
			(layers "*.Cu" "*.Mask")
			(remove_unused_layers no)
			(net "GND")
			(clearance 0.0508)
			(thermal_gap 0.0508)
		)
		(pad "A7" thru_hole circle
			(at 13.199872 0 180)
			(size 0.71628 0.71628)
			(drill 0.30988)
			(layers "*.Cu" "*.Mask")
			(remove_unused_layers no)
			(net "PRSNT_SWB_C_N")
			(clearance 0.0508)
			(thermal_gap 0.0508)
		)
		(pad "A8" thru_hole circle
			(at 15.40002 0.199898 180)
			(size 0.906272 0.906272)
			(drill 0.499872)
			(layers "*.Cu" "*.Mask")
			(remove_unused_layers no)
			(net "GND")
			(clearance 0.0508)
			(thermal_gap 0.0508)
		)
		(pad "A9" thru_hole circle
			(at 17.599914 0 180)
			(size 0.71628 0.71628)
			(drill 0.30988)
			(layers "*.Cu" "*.Mask")
			(remove_unused_layers no)
			(net "RST_GPU_FPGA_PEX_RST_N")
			(clearance 0.0508)
			(thermal_gap 0.0508)
		)
		(pad "A10" thru_hole circle
			(at 19.800062 0.199898 180)
			(size 0.906272 0.906272)
			(drill 0.499872)
			(layers "*.Cu" "*.Mask")
			(remove_unused_layers no)
			(net "GND")
			(clearance 0.0508)
			(thermal_gap 0.0508)
		)
		(pad "B1" thru_hole circle
			(at 0 1.299972 180)
			(size 0.906272 0.906272)
			(drill 0.499872)
			(layers "*.Cu" "*.Mask")
			(remove_unused_layers no)
			(net "GND")
			(clearance 0.0508)
			(thermal_gap 0.0508)
		)
		(pad "B3" thru_hole circle
			(at 4.400042 1.299972 180)
			(size 0.906272 0.906272)
			(drill 0.499872)
			(layers "*.Cu" "*.Mask")
			(remove_unused_layers no)
			(net "GND")
			(clearance 0.0508)
			(thermal_gap 0.0508)
		)
		(pad "B5" thru_hole circle
			(at 8.800084 1.299972 180)
			(size 0.906272 0.906272)
			(drill 0.499872)
			(layers "*.Cu" "*.Mask")
			(remove_unused_layers no)
			(net "GND")
			(clearance 0.0508)
			(thermal_gap 0.0508)
		)
		(pad "B7" thru_hole circle
			(at 13.199872 1.299972 180)
			(size 0.906272 0.906272)
			(drill 0.499872)
			(layers "*.Cu" "*.Mask")
			(remove_unused_layers no)
			(net "GND")
			(clearance 0.0508)
			(thermal_gap 0.0508)
		)
		(pad "B9" thru_hole circle
			(at 17.599914 1.299972 180)
			(size 0.906272 0.906272)
			(drill 0.499872)
			(layers "*.Cu" "*.Mask")
			(remove_unused_layers no)
			(net "GND")
			(clearance 0.0508)
			(thermal_gap 0.0508)
		)
		(pad "C9" thru_hole circle
			(at 17.599914 2.599944 180)
			(size 0.71628 0.71628)
			(drill 0.30988)
			(layers "*.Cu" "*.Mask")
			(remove_unused_layers no)
			(net "GPU_THERM_OVERT_R_N")
			(clearance 0.0508)
			(thermal_gap 0.0508)
		)
		(pad "D2" thru_hole circle
			(at 2.199894 4.100068 180)
			(size 0.906272 0.906272)
			(drill 0.499872)
			(layers "*.Cu" "*.Mask")
			(remove_unused_layers no)
			(net "GND")
			(clearance 0.0508)
			(thermal_gap 0.0508)
		)
		(pad "D4" thru_hole circle
			(at 6.599936 4.100068 180)
			(size 0.906272 0.906272)
			(drill 0.499872)
			(layers "*.Cu" "*.Mask")
			(remove_unused_layers no)
			(net "GND")
			(clearance 0.0508)
			(thermal_gap 0.0508)
		)
		(pad "D6" thru_hole circle
			(at 10.999978 4.100068 180)
			(size 0.906272 0.906272)
			(drill 0.499872)
			(layers "*.Cu" "*.Mask")
			(remove_unused_layers no)
			(net "GND")
			(clearance 0.0508)
			(thermal_gap 0.0508)
		)
		(pad "D8" thru_hole circle
			(at 15.40002 4.100068 180)
			(size 0.906272 0.906272)
			(drill 0.499872)
			(layers "*.Cu" "*.Mask")
			(remove_unused_layers no)
			(net "GND")
			(clearance 0.0508)
			(thermal_gap 0.0508)
		)
		(pad "D9" thru_hole circle
			(at 17.599914 3.899916 180)
			(size 0.71628 0.71628)
			(drill 0.30988)
			(layers "*.Cu" "*.Mask")
			(remove_unused_layers no)
			(net "GPU_PEX_STRAP0")
			(clearance 0.0508)
			(thermal_gap 0.0508)
		)
		(pad "D10" thru_hole circle
			(at 19.800062 4.100068 180)
			(size 0.906272 0.906272)
			(drill 0.499872)
			(layers "*.Cu" "*.Mask")
			(remove_unused_layers no)
			(net "GND")
			(clearance 0.0508)
			(thermal_gap 0.0508)
		)
		(pad "E1" thru_hole circle
			(at 0 5.199888 180)
			(size 0.906272 0.906272)
			(drill 0.499872)
			(layers "*.Cu" "*.Mask")
			(remove_unused_layers no)
			(net "GND")
			(clearance 0.0508)
			(thermal_gap 0.0508)
		)
		(pad "E3" thru_hole circle
			(at 4.400042 5.199888 180)
			(size 0.906272 0.906272)
			(drill 0.499872)
			(layers "*.Cu" "*.Mask")
			(remove_unused_layers no)
			(net "GND")
			(clearance 0.0508)
			(thermal_gap 0.0508)
		)
		(pad "E5" thru_hole circle
			(at 8.800084 5.199888 180)
			(size 0.906272 0.906272)
			(drill 0.499872)
			(layers "*.Cu" "*.Mask")
			(remove_unused_layers no)
			(net "GND")
			(clearance 0.0508)
			(thermal_gap 0.0508)
		)
		(pad "E7" thru_hole circle
			(at 13.199872 5.199888 180)
			(size 0.906272 0.906272)
			(drill 0.499872)
			(layers "*.Cu" "*.Mask")
			(remove_unused_layers no)
			(net "GND")
			(clearance 0.0508)
			(thermal_gap 0.0508)
		)
		(pad "E9" thru_hole circle
			(at 17.599914 5.199888 180)
			(size 0.906272 0.906272)
			(drill 0.499872)
			(layers "*.Cu" "*.Mask")
			(remove_unused_layers no)
			(net "GND")
			(clearance 0.0508)
			(thermal_gap 0.0508)
		)
		(pad "F9" thru_hole circle
			(at 17.599914 6.500114 180)
			(size 0.71628 0.71628)
			(drill 0.30988)
			(layers "*.Cu" "*.Mask")
			(remove_unused_layers no)
			(net "GPU_PWR_BRAKE_N")
			(clearance 0.0508)
			(thermal_gap 0.0508)
		)
		(pad "G2" thru_hole circle
			(at 2.199894 7.999984 180)
			(size 0.906272 0.906272)
			(drill 0.499872)
			(layers "*.Cu" "*.Mask")
			(remove_unused_layers no)
			(net "GND")
			(clearance 0.0508)
			(thermal_gap 0.0508)
		)
		(pad "G4" thru_hole circle
			(at 6.599936 7.999984 180)
			(size 0.906272 0.906272)
			(drill 0.499872)
			(layers "*.Cu" "*.Mask")
			(remove_unused_layers no)
			(net "GND")
			(clearance 0.0508)
			(thermal_gap 0.0508)
		)
		(pad "G6" thru_hole circle
			(at 10.999978 7.999984 180)
			(size 0.906272 0.906272)
			(drill 0.499872)
			(layers "*.Cu" "*.Mask")
			(remove_unused_layers no)
			(net "GND")
			(clearance 0.0508)
			(thermal_gap 0.0508)
		)
		(pad "G8" thru_hole circle
			(at 15.40002 7.999984 180)
			(size 0.906272 0.906272)
			(drill 0.499872)
			(layers "*.Cu" "*.Mask")
			(remove_unused_layers no)
			(net "GND")
			(clearance 0.0508)
			(thermal_gap 0.0508)
		)
		(pad "G9" thru_hole circle
			(at 17.599914 7.800086 180)
			(size 0.71628 0.71628)
			(drill 0.30988)
			(layers "*.Cu" "*.Mask")
			(remove_unused_layers no)
			(net "GPU_BASE_ID0")
			(clearance 0.0508)
			(thermal_gap 0.0508)
		)
		(pad "G10" thru_hole circle
			(at 19.800062 7.999984 180)
			(size 0.906272 0.906272)
			(drill 0.499872)
			(layers "*.Cu" "*.Mask")
			(remove_unused_layers no)
			(net "GND")
			(clearance 0.0508)
			(thermal_gap 0.0508)
		)
		(pad "H1" thru_hole circle
			(at 0 9.100058 180)
			(size 0.906272 0.906272)
			(drill 0.499872)
			(layers "*.Cu" "*.Mask")
			(remove_unused_layers no)
			(net "GND")
			(clearance 0.0508)
			(thermal_gap 0.0508)
		)
		(pad "H3" thru_hole circle
			(at 4.400042 9.100058 180)
			(size 0.906272 0.906272)
			(drill 0.499872)
			(layers "*.Cu" "*.Mask")
			(remove_unused_layers no)
			(net "GND")
			(clearance 0.0508)
			(thermal_gap 0.0508)
		)
		(pad "H5" thru_hole circle
			(at 8.800084 9.100058 180)
			(size 0.906272 0.906272)
			(drill 0.499872)
			(layers "*.Cu" "*.Mask")
			(remove_unused_layers no)
			(net "GND")
			(clearance 0.0508)
			(thermal_gap 0.0508)
		)
		(pad "H7" thru_hole circle
			(at 13.199872 9.100058 180)
			(size 0.906272 0.906272)
			(drill 0.499872)
			(layers "*.Cu" "*.Mask")
			(remove_unused_layers no)
			(net "GND")
			(clearance 0.0508)
			(thermal_gap 0.0508)
		)
		(pad "H9" thru_hole circle
			(at 17.599914 9.100058 180)
			(size 0.906272 0.906272)
			(drill 0.499872)
			(layers "*.Cu" "*.Mask")
			(remove_unused_layers no)
			(net "GND")
			(clearance 0.0508)
			(thermal_gap 0.0508)
		)
		(pad "H10" thru_hole circle
			(at 19.800062 9.299956 180)
			(size 0.71628 0.71628)
			(drill 0.30988)
			(layers "*.Cu" "*.Mask")
			(remove_unused_layers no)
			(net "GPU_BASE_FPGA_READY_R")
			(clearance 0.0508)
			(thermal_gap 0.0508)
		)
		(pad "I9" thru_hole circle
			(at 17.599914 10.40003 180)
			(size 0.71628 0.71628)
			(drill 0.30988)
			(layers "*.Cu" "*.Mask")
			(remove_unused_layers no)
			(net "TP_CLK_100M_MB_2_DN")
			(clearance 0.0508)
			(thermal_gap 0.0508)
		)
		(pad "I10" thru_hole circle
			(at 19.800062 10.599928 180)
			(size 0.71628 0.71628)
			(drill 0.30988)
			(layers "*.Cu" "*.Mask")
			(remove_unused_layers no)
			(net "GPU_PEX_STRAP1")
			(clearance 0.0508)
			(thermal_gap 0.0508)
		)
		(pad "J2" thru_hole circle
			(at 2.199894 11.8999 180)
			(size 0.906272 0.906272)
			(drill 0.499872)
			(layers "*.Cu" "*.Mask")
			(remove_unused_layers no)
			(net "GND")
			(clearance 0.0508)
			(thermal_gap 0.0508)
		)
		(pad "J4" thru_hole circle
			(at 6.599936 11.8999 180)
			(size 0.906272 0.906272)
			(drill 0.499872)
			(layers "*.Cu" "*.Mask")
			(remove_unused_layers no)
			(net "GND")
			(clearance 0.0508)
			(thermal_gap 0.0508)
		)
		(pad "J6" thru_hole circle
			(at 10.999978 11.8999 180)
			(size 0.906272 0.906272)
			(drill 0.499872)
			(layers "*.Cu" "*.Mask")
			(remove_unused_layers no)
			(net "GND")
			(clearance 0.0508)
			(thermal_gap 0.0508)
		)
		(pad "J8" thru_hole circle
			(at 15.40002 11.8999 180)
			(size 0.906272 0.906272)
			(drill 0.499872)
			(layers "*.Cu" "*.Mask")
			(remove_unused_layers no)
			(net "GND")
			(clearance 0.0508)
			(thermal_gap 0.0508)
		)
		(pad "J9" thru_hole circle
			(at 17.599914 11.700002 180)
			(size 0.71628 0.71628)
			(drill 0.30988)
			(layers "*.Cu" "*.Mask")
			(remove_unused_layers no)
			(net "TP_CLK_100M_MB_2_DP")
			(clearance 0.0508)
			(thermal_gap 0.0508)
		)
		(pad "J10" thru_hole circle
			(at 19.800062 11.8999 180)
			(size 0.906272 0.906272)
			(drill 0.499872)
			(layers "*.Cu" "*.Mask")
			(remove_unused_layers no)
			(net "GND")
			(clearance 0.0508)
			(thermal_gap 0.0508)
		)
		(pad "K1" thru_hole circle
			(at 0 12.999974 180)
			(size 0.906272 0.906272)
			(drill 0.499872)
			(layers "*.Cu" "*.Mask")
			(remove_unused_layers no)
			(net "GND")
			(clearance 0.0508)
			(thermal_gap 0.0508)
		)
		(pad "K3" thru_hole circle
			(at 4.400042 12.999974 180)
			(size 0.906272 0.906272)
			(drill 0.499872)
			(layers "*.Cu" "*.Mask")
			(remove_unused_layers no)
			(net "GND")
			(clearance 0.0508)
			(thermal_gap 0.0508)
		)
		(pad "K5" thru_hole circle
			(at 8.800084 12.999974 180)
			(size 0.906272 0.906272)
			(drill 0.499872)
			(layers "*.Cu" "*.Mask")
			(remove_unused_layers no)
			(net "GND")
			(clearance 0.0508)
			(thermal_gap 0.0508)
		)
		(pad "K7" thru_hole circle
			(at 13.199872 12.999974 180)
			(size 0.906272 0.906272)
			(drill 0.499872)
			(layers "*.Cu" "*.Mask")
			(remove_unused_layers no)
			(net "GND")
			(clearance 0.0508)
			(thermal_gap 0.0508)
		)
		(pad "K9" thru_hole circle
			(at 17.599914 12.999974 180)
			(size 0.906272 0.906272)
			(drill 0.499872)
			(layers "*.Cu" "*.Mask")
			(remove_unused_layers no)
			(net "GND")
			(clearance 0.0508)
			(thermal_gap 0.0508)
		)
		(pad "K10" thru_hole circle
			(at 19.800062 13.199872 180)
			(size 0.71628 0.71628)
			(drill 0.30988)
			(layers "*.Cu" "*.Mask")
			(remove_unused_layers no)
			(net "CLK_100M_GPU_FPGA_REF_DN")
			(clearance 0.0508)
			(thermal_gap 0.0508)
		)
		(pad "L9" thru_hole circle
			(at 17.599914 14.299946 180)
			(size 0.71628 0.71628)
			(drill 0.30988)
			(layers "*.Cu" "*.Mask")
			(remove_unused_layers no)
			(net "USB2_MB_BMC_DN")
			(clearance 0.0508)
			(thermal_gap 0.0508)
		)
		(pad "L10" thru_hole circle
			(at 19.800062 14.500098 180)
			(size 0.71628 0.71628)
			(drill 0.30988)
			(layers "*.Cu" "*.Mask")
			(remove_unused_layers no)
			(net "CLK_100M_GPU_FPGA_REF_DP")
			(clearance 0.0508)
			(thermal_gap 0.0508)
		)
		(pad "M1_2" thru_hole circle
			(at 2.199894 15.80007 180)
			(size 0.906272 0.906272)
			(drill 0.499872)
			(layers "*.Cu" "*.Mask")
			(remove_unused_layers no)
			(net "GND")
			(clearance 0.0508)
			(thermal_gap 0.0508)
		)
		(pad "M1_4" thru_hole circle
			(at 6.599936 15.80007 180)
			(size 0.906272 0.906272)
			(drill 0.499872)
			(layers "*.Cu" "*.Mask")
			(remove_unused_layers no)
			(net "GND")
			(clearance 0.0508)
			(thermal_gap 0.0508)
		)
		(pad "M1_6" thru_hole circle
			(at 10.999978 15.80007 180)
			(size 0.906272 0.906272)
			(drill 0.499872)
			(layers "*.Cu" "*.Mask")
			(remove_unused_layers no)
			(net "GND")
			(clearance 0.0508)
			(thermal_gap 0.0508)
		)
		(pad "M1_8" thru_hole circle
			(at 15.40002 15.80007 180)
			(size 0.906272 0.906272)
			(drill 0.499872)
			(layers "*.Cu" "*.Mask")
			(remove_unused_layers no)
			(net "GND")
			(clearance 0.0508)
			(thermal_gap 0.0508)
		)
		(pad "M1_10" thru_hole circle
			(at 19.800062 15.80007 180)
			(size 0.906272 0.906272)
			(drill 0.499872)
			(layers "*.Cu" "*.Mask")
			(remove_unused_layers no)
			(net "GND")
			(clearance 0.0508)
			(thermal_gap 0.0508)
		)
		(pad "M2_2" thru_hole circle
			(at 2.199894 26.2001 180)
			(size 0.906272 0.906272)
			(drill 0.499872)
			(layers "*.Cu" "*.Mask")
			(remove_unused_layers no)
			(net "GND")
			(clearance 0.0508)
			(thermal_gap 0.0508)
		)
		(pad "M2_4" thru_hole circle
			(at 6.599936 26.2001 180)
			(size 0.906272 0.906272)
			(drill 0.499872)
			(layers "*.Cu" "*.Mask")
			(remove_unused_layers no)
			(net "GND")
			(clearance 0.0508)
			(thermal_gap 0.0508)
		)
		(pad "M2_6" thru_hole circle
			(at 10.999978 26.2001 180)
			(size 0.906272 0.906272)
			(drill 0.499872)
			(layers "*.Cu" "*.Mask")
			(remove_unused_layers no)
			(net "GND")
			(clearance 0.0508)
			(thermal_gap 0.0508)
		)
		(pad "M2_8" thru_hole circle
			(at 15.40002 26.2001 180)
			(size 0.906272 0.906272)
			(drill 0.499872)
			(layers "*.Cu" "*.Mask")
			(remove_unused_layers no)
			(net "GND")
			(clearance 0.0508)
			(thermal_gap 0.0508)
		)
		(pad "M2_10" thru_hole circle
			(at 19.800062 26.2001 180)
			(size 0.906272 0.906272)
			(drill 0.499872)
			(layers "*.Cu" "*.Mask")
			(remove_unused_layers no)
			(net "GND")
			(clearance 0.0508)
			(thermal_gap 0.0508)
		)
		(pad "M9" thru_hole circle
			(at 17.599914 15.599918 180)
			(size 0.71628 0.71628)
			(drill 0.30988)
			(layers "*.Cu" "*.Mask")
			(remove_unused_layers no)
			(net "USB2_MB_BMC_DP")
			(clearance 0.0508)
			(thermal_gap 0.0508)
		)
		(pad "N1_1" thru_hole circle
			(at 0 16.89989 180)
			(size 0.906272 0.906272)
			(drill 0.499872)
			(layers "*.Cu" "*.Mask")
			(remove_unused_layers no)
			(net "GND")
			(clearance 0.0508)
			(thermal_gap 0.0508)
		)
		(pad "N1_3" thru_hole circle
			(at 4.400042 16.89989 180)
			(size 0.906272 0.906272)
			(drill 0.499872)
			(layers "*.Cu" "*.Mask")
			(remove_unused_layers no)
			(net "GND")
			(clearance 0.0508)
			(thermal_gap 0.0508)
		)
		(pad "N1_5" thru_hole circle
			(at 8.800084 16.89989 180)
			(size 0.906272 0.906272)
			(drill 0.499872)
			(layers "*.Cu" "*.Mask")
			(remove_unused_layers no)
			(net "GND")
			(clearance 0.0508)
			(thermal_gap 0.0508)
		)
		(pad "N1_7" thru_hole circle
			(at 13.199872 16.89989 180)
			(size 0.906272 0.906272)
			(drill 0.499872)
			(layers "*.Cu" "*.Mask")
			(remove_unused_layers no)
			(net "GND")
			(clearance 0.0508)
			(thermal_gap 0.0508)
		)
		(pad "N1_9" thru_hole circle
			(at 17.599914 16.89989 180)
			(size 0.906272 0.906272)
			(drill 0.499872)
			(layers "*.Cu" "*.Mask")
			(remove_unused_layers no)
			(net "GND")
			(clearance 0.0508)
			(thermal_gap 0.0508)
		)
		(pad "N2_1" thru_hole circle
			(at 0 27.29992 180)
			(size 0.906272 0.906272)
			(drill 0.499872)
			(layers "*.Cu" "*.Mask")
			(remove_unused_layers no)
			(net "GND")
			(clearance 0.0508)
			(thermal_gap 0.0508)
		)
		(pad "N2_3" thru_hole circle
			(at 4.400042 27.29992 180)
			(size 0.906272 0.906272)
			(drill 0.499872)
			(layers "*.Cu" "*.Mask")
			(remove_unused_layers no)
			(net "GND")
			(clearance 0.0508)
			(thermal_gap 0.0508)
		)
		(pad "N2_5" thru_hole circle
			(at 8.800084 27.29992 180)
			(size 0.906272 0.906272)
			(drill 0.499872)
			(layers "*.Cu" "*.Mask")
			(remove_unused_layers no)
			(net "GND")
			(clearance 0.0508)
			(thermal_gap 0.0508)
		)
		(pad "N2_7" thru_hole circle
			(at 13.199872 27.29992 180)
			(size 0.906272 0.906272)
			(drill 0.499872)
			(layers "*.Cu" "*.Mask")
			(remove_unused_layers no)
			(net "GND")
			(clearance 0.0508)
			(thermal_gap 0.0508)
		)
	)
)
